# T6G (Grand Teton) — schematic netlist excerpt (pin names and nets, part order shuffled) for the footprints in the layout excerpt that follows; sources: Cadence DE-HDL packaged netlist, KiCad conversion of 04192023_DAF0TMB3IC0_F0TG_MB_C_brd_V02_OCP.brd

R8084  Q_RES  0 5% CHIP  pkg 0402LF  page 92 : A = PWRGD_CHGL_CPU0_R1 ; B = PWRGD_CHGL_CPU0_R2
PR169  Q_RES  0 5% CHIP  pkg 0402LF  page 54 : A = SVID_PVDDCR_CPU0_P1_SVC_R ; B = SVID_PVDDCR_CPU0_P1_SVC
PC491  Q_CAPP  270UF 16V 20% OSCON  pkg THLF  page 194 : A = SW_P12V_AUX_PVDDCR_CPU0_P0_FLT ; B = GND

(kicad_pcb
	(version 20260206)
	(generator "pcbnew")
	(generator_version "10.0")
	(general
		(thickness 1.6)
		(legacy_teardrops no)
	)
	(paper "A4")
	(title_block
		(title "04192023_DAF0TMB3IC0_F0TG_MB_C_brd_V02_OCP.brd")
		(comment 1 "Grand Teton / footprints 1515-1517 of 8354")
	)
	(layers
		(0 "F.Cu" signal "TOP")
		(4 "In1.Cu" signal "GND")
		(6 "In2.Cu" signal "IN1")
		(8 "In3.Cu" signal "GND1")
		(10 "In4.Cu" signal "IN2")
		(12 "In5.Cu" signal "GND2")
		(14 "In6.Cu" signal "IN3")
		(16 "In7.Cu" signal "GND3")
		(18 "In8.Cu" signal "VCC")
		(20 "In9.Cu" signal "VCC1")
		(22 "In10.Cu" signal "GND4")
		(24 "In11.Cu" signal "IN4")
		(26 "In12.Cu" signal "GND5")
		(28 "In13.Cu" signal "IN5")
		(30 "In14.Cu" signal "GND6")
		(32 "In15.Cu" signal "IN6")
		(34 "In16.Cu" signal "GND7")
		(2 "B.Cu" signal "BOTTOM")
		(9 "F.Adhes" user "F.Adhesive")
		(11 "B.Adhes" user "B.Adhesive")
		(13 "F.Paste" user "Package Geometry/Pastemask Top")
		(15 "B.Paste" user "Package Geometry/Pastemask Bottom")
		(5 "F.SilkS" user "Ref Des/Silkscreen Top")
		(7 "B.SilkS" user "Ref Des/Silkscreen Bottom")
		(1 "F.Mask" user "Board Geometry/Soldermask Top")
		(3 "B.Mask" user "Board Geometry/Soldermask Bottom")
		(17 "Dwgs.User" user "User.Drawings")
		(19 "Cmts.User" user "User.Comments")
		(21 "Eco1.User" user "User.Eco1")
		(23 "Eco2.User" user "User.Eco2")
		(25 "Edge.Cuts" user "Board Geometry/Outline")
		(27 "Margin" user)
		(31 "F.CrtYd" user "Package Geometry/Place Bound Top")
		(29 "B.CrtYd" user "Package Geometry/Place Bound Bottom")
		(35 "F.Fab" user "Ref Des/Assembly Top")
		(33 "B.Fab" user "Ref Des/Assembly Bottom")
	)
	(footprint ""
		(layer "F.Cu")
		(at 144.834864 -194.567048 90)
		(property "Reference" "PR169"
			(at 0 0 90)
			(layer "F.SilkS")
			(hide yes)
			(effects
				(font
					(size 1.27 1.27)
				)
			)
		)
		(property "Value" ""
			(at 0 0 90)
			(layer "F.Fab")
			(effects
				(font
					(size 1.27 1.27)
				)
			)
		)
		(duplicate_pad_numbers_are_jumpers no)
		(fp_line
			(start 0.7874 -0.4064)
			(end 0.7874 0.4064)
			(stroke
				(width 0.1524)
				(type default)
			)
			(layer "F.SilkS")
		)
		(fp_line
			(start -0.7874 -0.4064)
			(end 0.7874 -0.4064)
			(stroke
				(width 0.1524)
				(type default)
			)
			(layer "F.SilkS")
		)
		(fp_line
			(start 0.7874 0.4064)
			(end -0.7874 0.4064)
			(stroke
				(width 0.1524)
				(type default)
			)
			(layer "F.SilkS")
		)
		(fp_line
			(start -0.7874 0.4064)
			(end -0.7874 -0.4064)
			(stroke
				(width 0.1524)
				(type default)
			)
			(layer "F.SilkS")
		)
		(fp_line
			(start -0.12065 -0.305054)
			(end -0.12065 -0.2794)
			(stroke
				(width 0.1)
				(type default)
			)
			(layer "F.Fab")
		)
		(fp_line
			(start -0.67945 -0.305054)
			(end -0.12065 -0.305054)
			(stroke
				(width 0.1)
				(type default)
			)
			(layer "F.Fab")
		)
		(fp_line
			(start 0.67945 -0.3048)
			(end 0.67945 0.3048)
			(stroke
				(width 0.1)
				(type default)
			)
			(layer "F.Fab")
		)
		(fp_line
			(start 0.12065 -0.3048)
			(end 0.67945 -0.3048)
			(stroke
				(width 0.1)
				(type default)
			)
			(layer "F.Fab")
		)
		(fp_line
			(start 0.12065 -0.2794)
			(end 0.12065 -0.3048)
			(stroke
				(width 0.1)
				(type default)
			)
			(layer "F.Fab")
		)
		(fp_line
			(start -0.12065 -0.2794)
			(end 0.12065 -0.2794)
			(stroke
				(width 0.1)
				(type default)
			)
			(layer "F.Fab")
		)
		(fp_line
			(start 0.120396 0.2794)
			(end -0.12065 0.2794)
			(stroke
				(width 0.1)
				(type default)
			)
			(layer "F.Fab")
		)
		(fp_line
			(start -0.12065 0.2794)
			(end -0.12065 0.3048)
			(stroke
				(width 0.1)
				(type default)
			)
			(layer "F.Fab")
		)
		(fp_line
			(start 0.67945 0.3048)
			(end 0.120396 0.3048)
			(stroke
				(width 0.1)
				(type default)
			)
			(layer "F.Fab")
		)
		(fp_line
			(start 0.120396 0.3048)
			(end 0.120396 0.2794)
			(stroke
				(width 0.1)
				(type default)
			)
			(layer "F.Fab")
		)
		(fp_line
			(start -0.12065 0.3048)
			(end -0.67945 0.3048)
			(stroke
				(width 0.1)
				(type default)
			)
			(layer "F.Fab")
		)
		(fp_line
			(start -0.67945 0.3048)
			(end -0.67945 -0.305054)
			(stroke
				(width 0.1)
				(type default)
			)
			(layer "F.Fab")
		)
		(pad "1" smd circle
			(at -0.40005 0 90)
			(size 0 0)
			(layers "F.Cu" "F.Mask" "F.Paste")
			(net "SVID_PVDDCR_CPU0_P1_SVC_R")
		)
		(pad "2" smd circle
			(at 0.40005 0 90)
			(size 0 0)
			(layers "F.Cu" "F.Mask" "F.Paste")
			(net "SVID_PVDDCR_CPU0_P1_SVC")
		)
	)
	(footprint ""
		(layer "F.Cu")
		(at 200.914 -102.362 180)
		(property "Reference" "R8084"
			(at 0 0 180)
			(layer "F.SilkS")
			(hide yes)
			(effects
				(font
					(size 1.27 1.27)
				)
			)
		)
		(property "Value" ""
			(at 0 0 180)
			(layer "F.Fab")
			(effects
				(font
					(size 1.27 1.27)
				)
			)
		)
		(duplicate_pad_numbers_are_jumpers no)
		(fp_line
			(start 0.7874 0.4064)
			(end -0.7874 0.4064)
			(stroke
				(width 0.1524)
				(type default)
			)
			(layer "F.SilkS")
		)
		(fp_line
			(start 0.7874 -0.4064)
			(end 0.7874 0.4064)
			(stroke
				(width 0.1524)
				(type default)
			)
			(layer "F.SilkS")
		)
		(fp_line
			(start -0.7874 0.4064)
			(end -0.7874 -0.4064)
			(stroke
				(width 0.1524)
				(type default)
			)
			(layer "F.SilkS")
		)
		(fp_line
			(start -0.7874 -0.4064)
			(end 0.7874 -0.4064)
			(stroke
				(width 0.1524)
				(type default)
			)
			(layer "F.SilkS")
		)
		(fp_line
			(start 0.67945 0.3048)
			(end 0.120396 0.3048)
			(stroke
				(width 0.1)
				(type default)
			)
			(layer "F.Fab")
		)
		(fp_line
			(start 0.67945 -0.3048)
			(end 0.67945 0.3048)
			(stroke
				(width 0.1)
				(type default)
			)
			(layer "F.Fab")
		)
		(fp_line
			(start 0.12065 -0.2794)
			(end 0.12065 -0.3048)
			(stroke
				(width 0.1)
				(type default)
			)
			(layer "F.Fab")
		)
		(fp_line
			(start 0.12065 -0.3048)
			(end 0.67945 -0.3048)
			(stroke
				(width 0.1)
				(type default)
			)
			(layer "F.Fab")
		)
		(fp_line
			(start 0.120396 0.3048)
			(end 0.120396 0.2794)
			(stroke
				(width 0.1)
				(type default)
			)
			(layer "F.Fab")
		)
		(fp_line
			(start 0.120396 0.2794)
			(end -0.12065 0.2794)
			(stroke
				(width 0.1)
				(type default)
			)
			(layer "F.Fab")
		)
		(fp_line
			(start -0.12065 0.3048)
			(end -0.67945 0.3048)
			(stroke
				(width 0.1)
				(type default)
			)
			(layer "F.Fab")
		)
		(fp_line
			(start -0.12065 0.2794)
			(end -0.12065 0.3048)
			(stroke
				(width 0.1)
				(type default)
			)
			(layer "F.Fab")
		)
		(fp_line
			(start -0.12065 -0.2794)
			(end 0.12065 -0.2794)
			(stroke
				(width 0.1)
				(type default)
			)
			(layer "F.Fab")
		)
		(fp_line
			(start -0.12065 -0.305054)
			(end -0.12065 -0.2794)
			(stroke
				(width 0.1)
				(type default)
			)
			(layer "F.Fab")
		)
		(fp_line
			(start -0.67945 0.3048)
			(end -0.67945 -0.305054)
			(stroke
				(width 0.1)
				(type default)
			)
			(layer "F.Fab")
		)
		(fp_line
			(start -0.67945 -0.305054)
			(end -0.12065 -0.305054)
			(stroke
				(width 0.1)
				(type default)
			)
			(layer "F.Fab")
		)
		(pad "1" smd circle
			(at -0.40005 0 180)
			(size 0 0)
			(layers "F.Cu" "F.Mask" "F.Paste")
			(net "PWRGD_CHGL_CPU0_R1")
		)
		(pad "2" smd circle
			(at 0.40005 0 180)
			(size 0 0)
			(layers "F.Cu" "F.Mask" "F.Paste")
			(net "PWRGD_CHGL_CPU0_R2")
		)
	)
	(footprint ""
		(layer "F.Cu")
		(at 377.869958 -162.59683 180)
		(property "Reference" "PC491"
			(at 2.807716 -2.902712 0)
			(unlocked yes)
			(layer "F.SilkS")
			(effects
				(font
					(size 0.7874 0.5842)
					(thickness 0.1524)
				)
				(justify left)
			)
		)
		(property "Value" ""
			(at 0 0 180)
			(layer "F.Fab")
			(effects
				(font
					(size 1.27 1.27)
				)
			)
		)
		(duplicate_pad_numbers_are_jumpers no)
		(fp_line
			(start -3.400044 1.249934)
			(end 3.400044 1.249934)
			(stroke
				(width 0.1524)
				(type default)
			)
			(layer "F.SilkS")
		)
		(fp_circle
			(center 0 1.249934)
			(end -3.400044 1.249934)
			(stroke
				(width 0.1524)
				(type default)
			)
			(fill no)
			(layer "F.SilkS")
		)
		(fp_poly
			(pts
				(arc
					(start 3.400044 1.249934)
					(mid 0 4.649978)
					(end -3.400044 1.249934)
				)
			)
			(stroke
				(width 0)
				(type default)
			)
			(fill yes)
			(layer "F.SilkS")
		)
		(fp_circle
			(center 0 1.249934)
			(end -3.400044 1.249934)
			(stroke
				(width 0.1)
				(type default)
			)
			(fill no)
			(layer "F.Fab")
		)
		(pad "1" thru_hole rect
			(at 0 0 180)
			(size 1.524 1.524)
			(drill 1.016)
			(layers "*.Cu" "*.Mask")
			(remove_unused_layers no)
			(net "SW_P12V_AUX_PVDDCR_CPU0_P0_FLT")
			(clearance 0)
			(padstack
				(mode front_inner_back)
				(layer "Inner"
					(shape circle)
					(size 1.524 1.524)
					(clearance 0)
				)
				(layer "B.Cu"
					(shape rect)
					(size 1.524 1.524)
					(clearance 0)
				)
			)
		)
		(pad "2" thru_hole circle
			(at 0 2.500122 180)
			(size 1.524 1.524)
			(drill 1.016)
			(layers "*.Cu" "*.Mask")
			(remove_unused_layers no)
			(net "GND")
			(clearance 0)
		)
	)
)
